(kicad_pcb
	(version 20260206)
	(generator "pcbnew")
	(generator_version "10.0")
	(general
		(thickness 1.6)
		(legacy_teardrops no)
	)
	(paper "A4")
	(title_block
		(title "01162023_DA0F0TEBIF0_F0T_Expander_BD_F_brd_V02_OCP.brd")
		(comment 1 "Grand Teton / footprints 3639-3645 of 9728")
	)
	(layers
		(0 "F.Cu" signal "TOP")
		(4 "In1.Cu" signal "GND")
		(6 "In2.Cu" signal "VCC")
		(8 "In3.Cu" signal "VCC1")
		(10 "In4.Cu" signal "GND1")
		(12 "In5.Cu" signal "IN1")
		(14 "In6.Cu" signal "GND2")
		(16 "In7.Cu" signal "IN2")
		(18 "In8.Cu" signal "GND3")
		(20 "In9.Cu" signal "IN3")
		(22 "In10.Cu" signal "GND4")
		(24 "In11.Cu" signal "IN4")
		(26 "In12.Cu" signal "GND5")
		(28 "In13.Cu" signal "IN5")
		(30 "In14.Cu" signal "GND6")
		(32 "In15.Cu" signal "IN6")
		(34 "In16.Cu" signal "GND7")
		(2 "B.Cu" signal "BOTTOM")
		(9 "F.Adhes" user "F.Adhesive")
		(11 "B.Adhes" user "B.Adhesive")
		(13 "F.Paste" user "Package Geometry/Pastemask Top")
		(15 "B.Paste" user "Package Geometry/Pastemask Bottom")
		(5 "F.SilkS" user "Ref Des/Silkscreen Top")
		(7 "B.SilkS" user "Ref Des/Silkscreen Bottom")
		(1 "F.Mask" user "Board Geometry/Soldermask Top")
		(3 "B.Mask" user "Board Geometry/Soldermask Bottom")
		(17 "Dwgs.User" user "User.Drawings")
		(19 "Cmts.User" user "User.Comments")
		(21 "Eco1.User" user "User.Eco1")
		(23 "Eco2.User" user "User.Eco2")
		(25 "Edge.Cuts" user "Board Geometry/Outline")
		(27 "Margin" user)
		(31 "F.CrtYd" user "Package Geometry/Place Bound Top")
		(29 "B.CrtYd" user "Package Geometry/Place Bound Bottom")
		(35 "F.Fab" user "Ref Des/Assembly Top")
		(33 "B.Fab" user "Ref Des/Assembly Bottom")
	)
	(footprint ""
		(layer "F.Cu")
		(at 350.380554 -87.216234)
		(property "Reference" "R1593"
			(at 0 0 0)
			(layer "F.SilkS")
			(hide yes)
			(effects
				(font
					(size 1.27 1.27)
				)
			)
		)
		(property "Value" ""
			(at 0 0 0)
			(layer "F.Fab")
			(effects
				(font
					(size 1.27 1.27)
				)
			)
		)
		(duplicate_pad_numbers_are_jumpers no)
		(fp_line
			(start -0.7874 -0.4064)
			(end 0.7874 -0.4064)
			(stroke
				(width 0.1524)
				(type default)
			)
			(layer "F.SilkS")
		)
		(fp_line
			(start -0.7874 0.4064)
			(end -0.7874 -0.4064)
			(stroke
				(width 0.1524)
				(type default)
			)
			(layer "F.SilkS")
		)
		(fp_line
			(start 0.7874 -0.4064)
			(end 0.7874 0.4064)
			(stroke
				(width 0.1524)
				(type default)
			)
			(layer "F.SilkS")
		)
		(fp_line
			(start 0.7874 0.4064)
			(end -0.7874 0.4064)
			(stroke
				(width 0.1524)
				(type default)
			)
			(layer "F.SilkS")
		)
		(fp_line
			(start -0.67945 -0.305054)
			(end -0.12065 -0.305054)
			(stroke
				(width 0.1)
				(type default)
			)
			(layer "F.Fab")
		)
		(fp_line
			(start -0.67945 0.3048)
			(end -0.67945 -0.305054)
			(stroke
				(width 0.1)
				(type default)
			)
			(layer "F.Fab")
		)
		(fp_line
			(start -0.12065 -0.305054)
			(end -0.12065 -0.2794)
			(stroke
				(width 0.1)
				(type default)
			)
			(layer "F.Fab")
		)
		(fp_line
			(start -0.12065 -0.2794)
			(end 0.12065 -0.2794)
			(stroke
				(width 0.1)
				(type default)
			)
			(layer "F.Fab")
		)
		(fp_line
			(start -0.12065 0.2794)
			(end -0.12065 0.3048)
			(stroke
				(width 0.1)
				(type default)
			)
			(layer "F.Fab")
		)
		(fp_line
			(start -0.12065 0.3048)
			(end -0.67945 0.3048)
			(stroke
				(width 0.1)
				(type default)
			)
			(layer "F.Fab")
		)
		(fp_line
			(start 0.120396 0.2794)
			(end -0.12065 0.2794)
			(stroke
				(width 0.1)
				(type default)
			)
			(layer "F.Fab")
		)
		(fp_line
			(start 0.120396 0.3048)
			(end 0.120396 0.2794)
			(stroke
				(width 0.1)
				(type default)
			)
			(layer "F.Fab")
		)
		(fp_line
			(start 0.12065 -0.3048)
			(end 0.67945 -0.3048)
			(stroke
				(width 0.1)
				(type default)
			)
			(layer "F.Fab")
		)
		(fp_line
			(start 0.12065 -0.2794)
			(end 0.12065 -0.3048)
			(stroke
				(width 0.1)
				(type default)
			)
			(layer "F.Fab")
		)
		(fp_line
			(start 0.67945 -0.3048)
			(end 0.67945 0.3048)
			(stroke
				(width 0.1)
				(type default)
			)
			(layer "F.Fab")
		)
		(fp_line
			(start 0.67945 0.3048)
			(end 0.120396 0.3048)
			(stroke
				(width 0.1)
				(type default)
			)
			(layer "F.Fab")
		)
		(pad "1" smd circle
			(at -0.40005 0)
			(size 0 0)
			(layers "F.Cu" "F.Mask" "F.Paste")
			(net "P3V3_AUX")
		)
		(pad "2" smd circle
			(at 0.40005 0)
			(size 0 0)
			(layers "F.Cu" "F.Mask" "F.Paste")
			(net "SMB_BIC_I2C9_MUX1_SSD9_R_SDA")
		)
	)
	(footprint ""
		(layer "F.Cu")
		(at 336.042 -143.891 180)
		(property "Reference" "R4803"
			(at 0 0 180)
			(layer "F.SilkS")
			(hide yes)
			(effects
				(font
					(size 1.27 1.27)
				)
			)
		)
		(property "Value" ""
			(at 0 0 180)
			(layer "F.Fab")
			(effects
				(font
					(size 1.27 1.27)
				)
			)
		)
		(duplicate_pad_numbers_are_jumpers no)
		(fp_line
			(start 0.7874 0.4064)
			(end -0.7874 0.4064)
			(stroke
				(width 0.1524)
				(type default)
			)
			(layer "F.SilkS")
		)
		(fp_line
			(start 0.7874 -0.4064)
			(end 0.7874 0.4064)
			(stroke
				(width 0.1524)
				(type default)
			)
			(layer "F.SilkS")
		)
		(fp_line
			(start -0.7874 0.4064)
			(end -0.7874 -0.4064)
			(stroke
				(width 0.1524)
				(type default)
			)
			(layer "F.SilkS")
		)
		(fp_line
			(start -0.7874 -0.4064)
			(end 0.7874 -0.4064)
			(stroke
				(width 0.1524)
				(type default)
			)
			(layer "F.SilkS")
		)
		(fp_line
			(start 0.67945 0.3048)
			(end 0.120396 0.3048)
			(stroke
				(width 0.1)
				(type default)
			)
			(layer "F.Fab")
		)
		(fp_line
			(start 0.67945 -0.3048)
			(end 0.67945 0.3048)
			(stroke
				(width 0.1)
				(type default)
			)
			(layer "F.Fab")
		)
		(fp_line
			(start 0.12065 -0.2794)
			(end 0.12065 -0.3048)
			(stroke
				(width 0.1)
				(type default)
			)
			(layer "F.Fab")
		)
		(fp_line
			(start 0.12065 -0.3048)
			(end 0.67945 -0.3048)
			(stroke
				(width 0.1)
				(type default)
			)
			(layer "F.Fab")
		)
		(fp_line
			(start 0.120396 0.3048)
			(end 0.120396 0.2794)
			(stroke
				(width 0.1)
				(type default)
			)
			(layer "F.Fab")
		)
		(fp_line
			(start 0.120396 0.2794)
			(end -0.12065 0.2794)
			(stroke
				(width 0.1)
				(type default)
			)
			(layer "F.Fab")
		)
		(fp_line
			(start -0.12065 0.3048)
			(end -0.67945 0.3048)
			(stroke
				(width 0.1)
				(type default)
			)
			(layer "F.Fab")
		)
		(fp_line
			(start -0.12065 0.2794)
			(end -0.12065 0.3048)
			(stroke
				(width 0.1)
				(type default)
			)
			(layer "F.Fab")
		)
		(fp_line
			(start -0.12065 -0.2794)
			(end 0.12065 -0.2794)
			(stroke
				(width 0.1)
				(type default)
			)
			(layer "F.Fab")
		)
		(fp_line
			(start -0.12065 -0.305054)
			(end -0.12065 -0.2794)
			(stroke
				(width 0.1)
				(type default)
			)
			(layer "F.Fab")
		)
		(fp_line
			(start -0.67945 0.3048)
			(end -0.67945 -0.305054)
			(stroke
				(width 0.1)
				(type default)
			)
			(layer "F.Fab")
		)
		(fp_line
			(start -0.67945 -0.305054)
			(end -0.12065 -0.305054)
			(stroke
				(width 0.1)
				(type default)
			)
			(layer "F.Fab")
		)
		(pad "1" smd circle
			(at -0.40005 0 180)
			(size 0 0)
			(layers "F.Cu" "F.Mask" "F.Paste")
			(net "SSD15_PEX_PWR_EN_R")
		)
		(pad "2" smd circle
			(at 0.40005 0 180)
			(size 0 0)
			(layers "F.Cu" "F.Mask" "F.Paste")
			(net "GND")
		)
	)
	(footprint ""
		(layer "F.Cu")
		(at 252.473968 -72.766682 90)
		(property "Reference" "PR7075"
			(at 0 0 90)
			(layer "F.SilkS")
			(hide yes)
			(effects
				(font
					(size 1.27 1.27)
				)
			)
		)
		(property "Value" ""
			(at 0 0 90)
			(layer "F.Fab")
			(effects
				(font
					(size 1.27 1.27)
				)
			)
		)
		(duplicate_pad_numbers_are_jumpers no)
		(fp_line
			(start 0.7874 -0.4064)
			(end 0.7874 0.4064)
			(stroke
				(width 0.1524)
				(type default)
			)
			(layer "F.SilkS")
		)
		(fp_line
			(start -0.7874 -0.4064)
			(end 0.7874 -0.4064)
			(stroke
				(width 0.1524)
				(type default)
			)
			(layer "F.SilkS")
		)
		(fp_line
			(start 0.7874 0.4064)
			(end -0.7874 0.4064)
			(stroke
				(width 0.1524)
				(type default)
			)
			(layer "F.SilkS")
		)
		(fp_line
			(start -0.7874 0.4064)
			(end -0.7874 -0.4064)
			(stroke
				(width 0.1524)
				(type default)
			)
			(layer "F.SilkS")
		)
		(fp_line
			(start -0.12065 -0.305054)
			(end -0.12065 -0.2794)
			(stroke
				(width 0.1)
				(type default)
			)
			(layer "F.Fab")
		)
		(fp_line
			(start -0.67945 -0.305054)
			(end -0.12065 -0.305054)
			(stroke
				(width 0.1)
				(type default)
			)
			(layer "F.Fab")
		)
		(fp_line
			(start 0.67945 -0.3048)
			(end 0.67945 0.3048)
			(stroke
				(width 0.1)
				(type default)
			)
			(layer "F.Fab")
		)
		(fp_line
			(start 0.12065 -0.3048)
			(end 0.67945 -0.3048)
			(stroke
				(width 0.1)
				(type default)
			)
			(layer "F.Fab")
		)
		(fp_line
			(start 0.12065 -0.2794)
			(end 0.12065 -0.3048)
			(stroke
				(width 0.1)
				(type default)
			)
			(layer "F.Fab")
		)
		(fp_line
			(start -0.12065 -0.2794)
			(end 0.12065 -0.2794)
			(stroke
				(width 0.1)
				(type default)
			)
			(layer "F.Fab")
		)
		(fp_line
			(start 0.120396 0.2794)
			(end -0.12065 0.2794)
			(stroke
				(width 0.1)
				(type default)
			)
			(layer "F.Fab")
		)
		(fp_line
			(start -0.12065 0.2794)
			(end -0.12065 0.3048)
			(stroke
				(width 0.1)
				(type default)
			)
			(layer "F.Fab")
		)
		(fp_line
			(start 0.67945 0.3048)
			(end 0.120396 0.3048)
			(stroke
				(width 0.1)
				(type default)
			)
			(layer "F.Fab")
		)
		(fp_line
			(start 0.120396 0.3048)
			(end 0.120396 0.2794)
			(stroke
				(width 0.1)
				(type default)
			)
			(layer "F.Fab")
		)
		(fp_line
			(start -0.12065 0.3048)
			(end -0.67945 0.3048)
			(stroke
				(width 0.1)
				(type default)
			)
			(layer "F.Fab")
		)
		(fp_line
			(start -0.67945 0.3048)
			(end -0.67945 -0.305054)
			(stroke
				(width 0.1)
				(type default)
			)
			(layer "F.Fab")
		)
		(pad "1" smd circle
			(at -0.40005 0 90)
			(size 0 0)
			(layers "F.Cu" "F.Mask" "F.Paste")
			(net "P12V_SSD8_CO_MODE")
		)
		(pad "2" smd circle
			(at 0.40005 0 90)
			(size 0 0)
			(layers "F.Cu" "F.Mask" "F.Paste")
			(net "GND")
		)
	)
	(footprint ""
		(layer "F.Cu")
		(at 368.814604 -66.32194 90)
		(property "Reference" "R6010"
			(at 0 0 90)
			(layer "F.SilkS")
			(hide yes)
			(effects
				(font
					(size 1.27 1.27)
				)
			)
		)
		(property "Value" ""
			(at 0 0 90)
			(layer "F.Fab")
			(effects
				(font
					(size 1.27 1.27)
				)
			)
		)
		(duplicate_pad_numbers_are_jumpers no)
		(fp_line
			(start 0.7874 -0.4064)
			(end 0.7874 0.4064)
			(stroke
				(width 0.1524)
				(type default)
			)
			(layer "F.SilkS")
		)
		(fp_line
			(start -0.7874 -0.4064)
			(end 0.7874 -0.4064)
			(stroke
				(width 0.1524)
				(type default)
			)
			(layer "F.SilkS")
		)
		(fp_line
			(start 0.7874 0.4064)
			(end -0.7874 0.4064)
			(stroke
				(width 0.1524)
				(type default)
			)
			(layer "F.SilkS")
		)
		(fp_line
			(start -0.7874 0.4064)
			(end -0.7874 -0.4064)
			(stroke
				(width 0.1524)
				(type default)
			)
			(layer "F.SilkS")
		)
		(fp_line
			(start -0.12065 -0.305054)
			(end -0.12065 -0.2794)
			(stroke
				(width 0.1)
				(type default)
			)
			(layer "F.Fab")
		)
		(fp_line
			(start -0.67945 -0.305054)
			(end -0.12065 -0.305054)
			(stroke
				(width 0.1)
				(type default)
			)
			(layer "F.Fab")
		)
		(fp_line
			(start 0.67945 -0.3048)
			(end 0.67945 0.3048)
			(stroke
				(width 0.1)
				(type default)
			)
			(layer "F.Fab")
		)
		(fp_line
			(start 0.12065 -0.3048)
			(end 0.67945 -0.3048)
			(stroke
				(width 0.1)
				(type default)
			)
			(layer "F.Fab")
		)
		(fp_line
			(start 0.12065 -0.2794)
			(end 0.12065 -0.3048)
			(stroke
				(width 0.1)
				(type default)
			)
			(layer "F.Fab")
		)
		(fp_line
			(start -0.12065 -0.2794)
			(end 0.12065 -0.2794)
			(stroke
				(width 0.1)
				(type default)
			)
			(layer "F.Fab")
		)
		(fp_line
			(start 0.120396 0.2794)
			(end -0.12065 0.2794)
			(stroke
				(width 0.1)
				(type default)
			)
			(layer "F.Fab")
		)
		(fp_line
			(start -0.12065 0.2794)
			(end -0.12065 0.3048)
			(stroke
				(width 0.1)
				(type default)
			)
			(layer "F.Fab")
		)
		(fp_line
			(start 0.67945 0.3048)
			(end 0.120396 0.3048)
			(stroke
				(width 0.1)
				(type default)
			)
			(layer "F.Fab")
		)
		(fp_line
			(start 0.120396 0.3048)
			(end 0.120396 0.2794)
			(stroke
				(width 0.1)
				(type default)
			)
			(layer "F.Fab")
		)
		(fp_line
			(start -0.12065 0.3048)
			(end -0.67945 0.3048)
			(stroke
				(width 0.1)
				(type default)
			)
			(layer "F.Fab")
		)
		(fp_line
			(start -0.67945 0.3048)
			(end -0.67945 -0.305054)
			(stroke
				(width 0.1)
				(type default)
			)
			(layer "F.Fab")
		)
		(pad "1" smd circle
			(at -0.40005 0 90)
			(size 0 0)
			(layers "F.Cu" "F.Mask" "F.Paste")
			(net "SSD12_PWR_EN_R")
		)
		(pad "2" smd circle
			(at 0.40005 0 90)
			(size 0 0)
			(layers "F.Cu" "F.Mask" "F.Paste")
			(net "P12V_SSD12_CO_EN")
		)
	)
	(footprint ""
		(layer "F.Cu")
		(at 288.079942 -142.9512 180)
		(property "Reference" "R213"
			(at 0 0 180)
			(layer "F.SilkS")
			(hide yes)
			(effects
				(font
					(size 1.27 1.27)
				)
			)
		)
		(property "Value" ""
			(at 0 0 180)
			(layer "F.Fab")
			(effects
				(font
					(size 1.27 1.27)
				)
			)
		)
		(duplicate_pad_numbers_are_jumpers no)
		(fp_line
			(start 0.7874 0.4064)
			(end -0.7874 0.4064)
			(stroke
				(width 0.1524)
				(type default)
			)
			(layer "F.SilkS")
		)
		(fp_line
			(start 0.7874 -0.4064)
			(end 0.7874 0.4064)
			(stroke
				(width 0.1524)
				(type default)
			)
			(layer "F.SilkS")
		)
		(fp_line
			(start -0.7874 0.4064)
			(end -0.7874 -0.4064)
			(stroke
				(width 0.1524)
				(type default)
			)
			(layer "F.SilkS")
		)
		(fp_line
			(start -0.7874 -0.4064)
			(end 0.7874 -0.4064)
			(stroke
				(width 0.1524)
				(type default)
			)
			(layer "F.SilkS")
		)
		(fp_line
			(start 0.67945 0.3048)
			(end 0.120396 0.3048)
			(stroke
				(width 0.1)
				(type default)
			)
			(layer "F.Fab")
		)
		(fp_line
			(start 0.67945 -0.3048)
			(end 0.67945 0.3048)
			(stroke
				(width 0.1)
				(type default)
			)
			(layer "F.Fab")
		)
		(fp_line
			(start 0.12065 -0.2794)
			(end 0.12065 -0.3048)
			(stroke
				(width 0.1)
				(type default)
			)
			(layer "F.Fab")
		)
		(fp_line
			(start 0.12065 -0.3048)
			(end 0.67945 -0.3048)
			(stroke
				(width 0.1)
				(type default)
			)
			(layer "F.Fab")
		)
		(fp_line
			(start 0.120396 0.3048)
			(end 0.120396 0.2794)
			(stroke
				(width 0.1)
				(type default)
			)
			(layer "F.Fab")
		)
		(fp_line
			(start 0.120396 0.2794)
			(end -0.12065 0.2794)
			(stroke
				(width 0.1)
				(type default)
			)
			(layer "F.Fab")
		)
		(fp_line
			(start -0.12065 0.3048)
			(end -0.67945 0.3048)
			(stroke
				(width 0.1)
				(type default)
			)
			(layer "F.Fab")
		)
		(fp_line
			(start -0.12065 0.2794)
			(end -0.12065 0.3048)
			(stroke
				(width 0.1)
				(type default)
			)
			(layer "F.Fab")
		)
		(fp_line
			(start -0.12065 -0.2794)
			(end 0.12065 -0.2794)
			(stroke
				(width 0.1)
				(type default)
			)
			(layer "F.Fab")
		)
		(fp_line
			(start -0.12065 -0.305054)
			(end -0.12065 -0.2794)
			(stroke
				(width 0.1)
				(type default)
			)
			(layer "F.Fab")
		)
		(fp_line
			(start -0.67945 0.3048)
			(end -0.67945 -0.305054)
			(stroke
				(width 0.1)
				(type default)
			)
			(layer "F.Fab")
		)
		(fp_line
			(start -0.67945 -0.305054)
			(end -0.12065 -0.305054)
			(stroke
				(width 0.1)
				(type default)
			)
			(layer "F.Fab")
		)
		(pad "1" smd circle
			(at -0.40005 0 180)
			(size 0 0)
			(layers "F.Cu" "F.Mask" "F.Paste")
			(net "P3V3_NIC4")
		)
		(pad "2" smd circle
			(at 0.40005 0 180)
			(size 0 0)
			(layers "F.Cu" "F.Mask" "F.Paste")
			(net "SMB_NIC4_LS_SCL")
		)
	)
	(footprint ""
		(layer "F.Cu")
		(at 259.400294 -256.478786)
		(property "Reference" "C3414"
			(at 0 0 0)
			(layer "F.SilkS")
			(hide yes)
			(effects
				(font
					(size 1.27 1.27)
				)
			)
		)
		(property "Value" ""
			(at 0 0 0)
			(layer "F.Fab")
			(effects
				(font
					(size 1.27 1.27)
				)
			)
		)
		(duplicate_pad_numbers_are_jumpers no)
		(fp_line
			(start -0.299974 -0.150114)
			(end 0.299974 -0.150114)
			(stroke
				(width 0.1)
				(type default)
			)
			(layer "F.Fab")
		)
		(fp_line
			(start -0.299974 0.150114)
			(end -0.299974 -0.150114)
			(stroke
				(width 0.1)
				(type default)
			)
			(layer "F.Fab")
		)
		(fp_line
			(start 0.299974 -0.150114)
			(end 0.299974 0.150114)
			(stroke
				(width 0.1)
				(type default)
			)
			(layer "F.Fab")
		)
		(fp_line
			(start 0.299974 0.150114)
			(end -0.299974 0.150114)
			(stroke
				(width 0.1)
				(type default)
			)
			(layer "F.Fab")
		)
		(pad "1" smd rect
			(at -0.2667 0)
			(size 0.3048 0.381)
			(layers "F.Cu" "F.Mask" "F.Paste")
			(net "P1V8_PLL0_PEX2")
		)
		(pad "2" smd rect
			(at 0.2667 0)
			(size 0.3048 0.381)
			(layers "F.Cu" "F.Mask" "F.Paste")
			(net "GND")
		)
	)
	(footprint ""
		(layer "F.Cu")
		(at 13.805154 -376.525282 -90)
		(property "Reference" "R6752"
			(at 0 0 270)
			(layer "F.SilkS")
			(hide yes)
			(effects
				(font
					(size 1.27 1.27)
				)
			)
		)
		(property "Value" ""
			(at 0 0 270)
			(layer "F.Fab")
			(effects
				(font
					(size 1.27 1.27)
				)
			)
		)
		(duplicate_pad_numbers_are_jumpers no)
		(fp_line
			(start 0.7874 0.4064)
			(end -0.454406 0.4064)
			(stroke
				(width 0.1524)
				(type default)
			)
			(layer "F.SilkS")
		)
		(fp_line
			(start -0.363982 -0.4064)
			(end 0.7874 -0.4064)
			(stroke
				(width 0.1524)
				(type default)
			)
			(layer "F.SilkS")
		)
		(fp_line
			(start 0.7874 -0.4064)
			(end 0.7874 0.4064)
			(stroke
				(width 0.1524)
				(type default)
			)
			(layer "F.SilkS")
		)
		(fp_line
			(start -0.67945 0.3048)
			(end -0.67945 -0.305054)
			(stroke
				(width 0.1)
				(type default)
			)
			(layer "F.Fab")
		)
		(fp_line
			(start -0.12065 0.3048)
			(end -0.67945 0.3048)
			(stroke
				(width 0.1)
				(type default)
			)
			(layer "F.Fab")
		)
		(fp_line
			(start 0.120396 0.3048)
			(end 0.120396 0.2794)
			(stroke
				(width 0.1)
				(type default)
			)
			(layer "F.Fab")
		)
		(fp_line
			(start 0.67945 0.3048)
			(end 0.120396 0.3048)
			(stroke
				(width 0.1)
				(type default)
			)
			(layer "F.Fab")
		)
		(fp_line
			(start -0.12065 0.2794)
			(end -0.12065 0.3048)
			(stroke
				(width 0.1)
				(type default)
			)
			(layer "F.Fab")
		)
		(fp_line
			(start 0.120396 0.2794)
			(end -0.12065 0.2794)
			(stroke
				(width 0.1)
				(type default)
			)
			(layer "F.Fab")
		)
		(fp_line
			(start -0.12065 -0.2794)
			(end 0.12065 -0.2794)
			(stroke
				(width 0.1)
				(type default)
			)
			(layer "F.Fab")
		)
		(fp_line
			(start 0.12065 -0.2794)
			(end 0.12065 -0.3048)
			(stroke
				(width 0.1)
				(type default)
			)
			(layer "F.Fab")
		)
		(fp_line
			(start 0.12065 -0.3048)
			(end 0.67945 -0.3048)
			(stroke
				(width 0.1)
				(type default)
			)
			(layer "F.Fab")
		)
		(fp_line
			(start 0.67945 -0.3048)
			(end 0.67945 0.3048)
			(stroke
				(width 0.1)
				(type default)
			)
			(layer "F.Fab")
		)
		(fp_line
			(start -0.67945 -0.305054)
			(end -0.12065 -0.305054)
			(stroke
				(width 0.1)
				(type default)
			)
			(layer "F.Fab")
		)
		(fp_line
			(start -0.12065 -0.305054)
			(end -0.12065 -0.2794)
			(stroke
				(width 0.1)
				(type default)
			)
			(layer "F.Fab")
		)
		(pad "1" smd circle
			(at -0.40005 0 270)
			(size 0 0)
			(layers "F.Cu" "F.Mask" "F.Paste")
			(net "USB2_GPU_HMC_USB8042_DP")
		)
		(pad "2" smd circle
			(at 0.40005 0 270)
			(size 0 0)
			(layers "F.Cu" "F.Mask" "F.Paste")
			(net "GND")
		)
	)
)
